(kicad_pcb
	(version 20260206)
	(generator "pcbnew")
	(generator_version "10.0")
	(general
		(thickness 1.6)
		(legacy_teardrops no)
	)
	(paper "A4")
	(title_block
		(title "15969-1a.1015WZS0858.brd")
		(comment 1 "Tioga Pass / footprints 89-92 of 295")
	)
	(layers
		(0 "F.Cu" signal "TOP")
		(4 "In1.Cu" signal "L2GND")
		(6 "In2.Cu" signal "L3")
		(8 "In3.Cu" signal "L4")
		(10 "In4.Cu" signal "L5GND")
		(2 "B.Cu" signal "BOTTOM")
		(9 "F.Adhes" user "F.Adhesive")
		(11 "B.Adhes" user "B.Adhesive")
		(13 "F.Paste" user "Package Geometry/Pastemask Top")
		(15 "B.Paste" user "Package Geometry/Pastemask Bottom")
		(5 "F.SilkS" user "Ref Des/Silkscreen Top")
		(7 "B.SilkS" user "Ref Des/Silkscreen Bottom")
		(1 "F.Mask" user "Board Geometry/Soldermask Top")
		(3 "B.Mask" user "Board Geometry/Soldermask Bottom")
		(17 "Dwgs.User" user "User.Drawings")
		(19 "Cmts.User" user "User.Comments")
		(21 "Eco1.User" user "User.Eco1")
		(23 "Eco2.User" user "User.Eco2")
		(25 "Edge.Cuts" user "Board Geometry/Outline")
		(27 "Margin" user)
		(31 "F.CrtYd" user "Package Geometry/Place Bound Top")
		(29 "B.CrtYd" user "Package Geometry/Place Bound Bottom")
		(35 "F.Fab" user "Ref Des/Assembly Top")
		(33 "B.Fab" user "Ref Des/Assembly Bottom")
	)
	(footprint ""
		(layer "F.Cu")
		(at 34.7472 -19.177 -90)
		(property "Reference" "TC4"
			(at 0 0 270)
			(layer "F.SilkS")
			(hide yes)
			(effects
				(font
					(size 1.27 1.27)
				)
			)
		)
		(property "Value" "SE100U25VM-10GP"
			(at 0 -9.0932 270)
			(unlocked yes)
			(layer "F.Fab")
			(hide yes)
			(effects
				(font
					(size 1.016 1.016)
					(thickness 0.1524)
				)
			)
		)
		(property "Device Type" "SE341618H315"
			(at 0 -10.6172 270)
			(unlocked yes)
			(layer "F.Fab")
			(hide yes)
			(effects
				(font
					(size 1.016 1.016)
					(thickness 0.1524)
				)
			)
		)
		(duplicate_pad_numbers_are_jumpers no)
		(fp_line
			(start -3.556 4.4831)
			(end -3.556 -3.4671)
			(stroke
				(width 0.1524)
				(type default)
			)
			(layer "F.SilkS")
		)
		(fp_line
			(start 3.556 4.4831)
			(end -3.556 4.4831)
			(stroke
				(width 0.1524)
				(type default)
			)
			(layer "F.SilkS")
		)
		(fp_line
			(start -3.556 -3.4671)
			(end -2.54 -4.4831)
			(stroke
				(width 0.1524)
				(type default)
			)
			(layer "F.SilkS")
		)
		(fp_line
			(start 3.556 -3.4671)
			(end 3.556 4.4831)
			(stroke
				(width 0.1524)
				(type default)
			)
			(layer "F.SilkS")
		)
		(fp_line
			(start -2.54 -4.4831)
			(end 2.54 -4.4831)
			(stroke
				(width 0.1524)
				(type default)
			)
			(layer "F.SilkS")
		)
		(fp_line
			(start 2.54 -4.4831)
			(end 3.556 -3.4671)
			(stroke
				(width 0.1524)
				(type default)
			)
			(layer "F.SilkS")
		)
		(fp_rect
			(start -3.81 4.7371)
			(end 3.81 -4.7371)
			(stroke
				(width 0)
				(type default)
			)
			(fill no)
			(layer "F.CrtYd")
		)
		(fp_rect
			(start -3.81 4.7371)
			(end 3.81 -4.7371)
			(stroke
				(width 0)
				(type default)
			)
			(fill no)
			(layer "F.Fab")
		)
		(pad "1" smd rect
			(at 0 -2.4384 270)
			(size 1.5494 3.5814)
			(layers "F.Cu" "F.Mask" "F.Paste")
			(net "P3V3")
		)
		(pad "2" smd rect
			(at 0 2.4384 270)
			(size 1.5494 3.5814)
			(layers "F.Cu" "F.Mask" "F.Paste")
			(net "GND")
		)
	)
	(footprint ""
		(layer "F.Cu")
		(at 118.8212 -30.2006 90)
		(property "Reference" "RU23"
			(at 0 0 90)
			(layer "F.SilkS")
			(hide yes)
			(effects
				(font
					(size 1.27 1.27)
				)
			)
		)
		(property "Value" "10KR2F-2-GP"
			(at 0.064008 -3.993896 90)
			(unlocked yes)
			(layer "F.Fab")
			(hide yes)
			(effects
				(font
					(size 1.016 1.016)
					(thickness 0.1524)
				)
			)
		)
		(property "Device Type" "R402H16"
			(at 0.064008 -5.517896 90)
			(unlocked yes)
			(layer "F.Fab")
			(hide yes)
			(effects
				(font
					(size 1.016 1.016)
					(thickness 0.1524)
				)
			)
		)
		(duplicate_pad_numbers_are_jumpers no)
		(fp_line
			(start 0.508 -0.9398)
			(end -0.508 -0.9398)
			(stroke
				(width 0.1524)
				(type default)
			)
			(layer "F.SilkS")
		)
		(fp_line
			(start -0.508 -0.9398)
			(end -0.508 0.9398)
			(stroke
				(width 0.1524)
				(type default)
			)
			(layer "F.SilkS")
		)
		(fp_rect
			(start -0.508 0.9398)
			(end 0.508 -0.9398)
			(stroke
				(width 0)
				(type default)
			)
			(fill no)
			(layer "F.CrtYd")
		)
		(fp_rect
			(start -0.508 0.9398)
			(end 0.508 -0.9398)
			(stroke
				(width 0)
				(type default)
			)
			(fill no)
			(layer "F.Fab")
		)
		(pad "1" smd custom
			(at 0 -0.4445 90)
			(size 0.1397 0.1397)
			(layers "F.Cu" "F.Mask" "F.Paste")
			(net "P3V3_USB_HUB")
			(options
				(clearance outline)
				(anchor circle)
			)
			(primitives
				(gr_poly
					(pts
						(arc
							(start -0.1778 -0.2794)
							(mid -0.249642 -0.249642)
							(end -0.2794 -0.1778)
						)
						(arc
							(start -0.2794 0.1778)
							(mid -0.249642 0.249642)
							(end -0.1778 0.2794)
						)
						(arc
							(start 0.1778 0.2794)
							(mid 0.249642 0.249642)
							(end 0.2794 0.1778)
						)
						(arc
							(start 0.2794 -0.1778)
							(mid 0.249642 -0.249642)
							(end 0.1778 -0.2794)
						)
					)
					(width 0)
					(fill yes)
				)
			)
		)
		(pad "2" smd custom
			(at 0 0.4445 90)
			(size 0.1397 0.1397)
			(layers "F.Cu" "F.Mask" "F.Paste")
			(net "TP_USB_DP3")
			(options
				(clearance outline)
				(anchor circle)
			)
			(primitives
				(gr_poly
					(pts
						(arc
							(start -0.1778 -0.2794)
							(mid -0.249642 -0.249642)
							(end -0.2794 -0.1778)
						)
						(arc
							(start -0.2794 0.1778)
							(mid -0.249642 0.249642)
							(end -0.1778 0.2794)
						)
						(arc
							(start 0.1778 0.2794)
							(mid 0.249642 0.249642)
							(end 0.2794 0.1778)
						)
						(arc
							(start 0.2794 -0.1778)
							(mid 0.249642 -0.249642)
							(end 0.1778 -0.2794)
						)
					)
					(width 0)
					(fill yes)
				)
			)
		)
	)
	(footprint ""
		(layer "F.Cu")
		(at 126.7968 -5.9944 180)
		(property "Reference" "U21"
			(at 0 0 180)
			(layer "F.SilkS")
			(hide yes)
			(effects
				(font
					(size 1.27 1.27)
				)
			)
		)
		(property "Value" "PCA9555PW-GP"
			(at 0 -12.1412 180)
			(unlocked yes)
			(layer "F.Fab")
			(hide yes)
			(effects
				(font
					(size 1.016 1.016)
					(thickness 0.1524)
				)
			)
		)
		(property "Device Type" "TSOIC24H44"
			(at 0 -13.6652 180)
			(unlocked yes)
			(layer "F.Fab")
			(hide yes)
			(effects
				(font
					(size 1.016 1.016)
					(thickness 0.1524)
				)
			)
		)
		(duplicate_pad_numbers_are_jumpers no)
		(fp_line
			(start 3.683 1.778)
			(end -4.1148 1.778)
			(stroke
				(width 0.1524)
				(type default)
			)
			(layer "F.SilkS")
		)
		(fp_line
			(start 3.683 -1.778)
			(end 3.683 1.778)
			(stroke
				(width 0.1524)
				(type default)
			)
			(layer "F.SilkS")
		)
		(fp_line
			(start -3.8354 0)
			(end -4.1148 0.2794)
			(stroke
				(width 0.1524)
				(type default)
			)
			(layer "F.SilkS")
		)
		(fp_line
			(start -3.8354 0)
			(end -4.1148 -0.2794)
			(stroke
				(width 0.1524)
				(type default)
			)
			(layer "F.SilkS")
		)
		(fp_line
			(start -4.0386 1.778)
			(end -4.0386 3.556)
			(stroke
				(width 0.3556)
				(type default)
			)
			(layer "F.SilkS")
		)
		(fp_line
			(start -4.1148 -1.778)
			(end 3.683 -1.778)
			(stroke
				(width 0.1524)
				(type default)
			)
			(layer "F.SilkS")
		)
		(fp_line
			(start -4.1148 -1.778)
			(end -4.1148 1.778)
			(stroke
				(width 0.1524)
				(type default)
			)
			(layer "F.SilkS")
		)
		(fp_poly
			(pts
				(xy -3.7592 -1.778) (xy 3.683 -1.778) (xy 3.683 1.778) (xy -3.7592 1.778)
			)
			(stroke
				(width 0)
				(type default)
			)
			(fill yes)
			(layer "F.SilkS")
		)
		(fp_poly
			(pts
				(xy -4.22656 3.81) (xy 4.22656 3.81) (xy 4.22656 -3.81) (xy -4.22656 -3.81)
			)
			(stroke
				(width 0)
				(type default)
			)
			(fill no)
			(layer "F.CrtYd")
		)
		(fp_poly
			(pts
				(xy -4.22656 -3.81) (xy 4.22656 -3.81) (xy 4.22656 3.81) (xy -4.22656 3.81)
			)
			(stroke
				(width 0)
				(type default)
			)
			(fill no)
			(layer "F.Fab")
		)
		(pad "1" smd rect
			(at -3.57632 2.8194 180)
			(size 0.3556 1.524)
			(layers "F.Cu" "F.Mask" "F.Paste")
			(net "GPIO_P_EXP_INT_N")
		)
		(pad "2" smd rect
			(at -2.92608 2.8194 180)
			(size 0.3556 1.524)
			(layers "F.Cu" "F.Mask" "F.Paste")
			(net "GPIO_P_EXP_A1")
		)
		(pad "3" smd rect
			(at -2.27584 2.8194 180)
			(size 0.3556 1.524)
			(layers "F.Cu" "F.Mask" "F.Paste")
			(net "GPIO_P_EXP_A2")
		)
		(pad "4" smd rect
			(at -1.6256 2.8194 180)
			(size 0.3556 1.524)
			(layers "F.Cu" "F.Mask" "F.Paste")
			(net "PCIE_SLOT2_PRSNT2_1_N")
		)
		(pad "5" smd rect
			(at -0.97536 2.8194 180)
			(size 0.3556 1.524)
			(layers "F.Cu" "F.Mask" "F.Paste")
			(net "PCIE_SLOT2_PRSNT2_2_N")
		)
		(pad "6" smd rect
			(at -0.32512 2.8194 180)
			(size 0.3556 1.524)
			(layers "F.Cu" "F.Mask" "F.Paste")
			(net "PCIE_SLOT2_PRSNT2_3_N")
		)
		(pad "7" smd rect
			(at 0.32512 2.8194 180)
			(size 0.3556 1.524)
			(layers "F.Cu" "F.Mask" "F.Paste")
			(net "PCIE_SLOT2_PRSNT2_4_N")
		)
		(pad "8" smd rect
			(at 0.97536 2.8194 180)
			(size 0.3556 1.524)
			(layers "F.Cu" "F.Mask" "F.Paste")
			(net "PCIE_SLOT3_PRSNT2_1_N")
		)
		(pad "9" smd rect
			(at 1.6256 2.8194 180)
			(size 0.3556 1.524)
			(layers "F.Cu" "F.Mask" "F.Paste")
			(net "PCIE_SLOT3_PRSNT2_2_N")
		)
		(pad "10" smd rect
			(at 2.27584 2.8194 180)
			(size 0.3556 1.524)
			(layers "F.Cu" "F.Mask" "F.Paste")
			(net "PCIE_SLOT3_PRSNT2_3_N")
		)
		(pad "11" smd rect
			(at 2.92608 2.8194 180)
			(size 0.3556 1.524)
			(layers "F.Cu" "F.Mask" "F.Paste")
			(net "PCIE_SLOT3_PRSNT2_4_N")
		)
		(pad "12" smd rect
			(at 3.57632 2.8194 180)
			(size 0.3556 1.524)
			(layers "F.Cu" "F.Mask" "F.Paste")
			(net "GND")
		)
		(pad "13" smd rect
			(at 3.57632 -2.8194 180)
			(size 0.3556 1.524)
			(layers "F.Cu" "F.Mask" "F.Paste")
			(net "GPIO_P_IO1_0")
		)
		(pad "14" smd rect
			(at 2.92608 -2.8194 180)
			(size 0.3556 1.524)
			(layers "F.Cu" "F.Mask" "F.Paste")
			(net "FM_SLT_CFG0")
		)
		(pad "15" smd rect
			(at 2.27584 -2.8194 180)
			(size 0.3556 1.524)
			(layers "F.Cu" "F.Mask" "F.Paste")
			(net "FM_SLT_CFG1")
		)
		(pad "16" smd rect
			(at 1.6256 -2.8194 180)
			(size 0.3556 1.524)
			(layers "F.Cu" "F.Mask" "F.Paste")
			(net "GPIO_P_IO1_3")
		)
		(pad "17" smd rect
			(at 0.97536 -2.8194 180)
			(size 0.3556 1.524)
			(layers "F.Cu" "F.Mask" "F.Paste")
			(net "GPIO_P_IO1_4")
		)
		(pad "18" smd rect
			(at 0.32512 -2.8194 180)
			(size 0.3556 1.524)
			(layers "F.Cu" "F.Mask" "F.Paste")
			(net "GPIO_P_IO1_5")
		)
		(pad "19" smd rect
			(at -0.32512 -2.8194 180)
			(size 0.3556 1.524)
			(layers "F.Cu" "F.Mask" "F.Paste")
			(net "GPIO_P_IO1_6")
		)
		(pad "20" smd rect
			(at -0.97536 -2.8194 180)
			(size 0.3556 1.524)
			(layers "F.Cu" "F.Mask" "F.Paste")
			(net "GPIO_P_IO1_7")
		)
		(pad "21" smd rect
			(at -1.6256 -2.8194 180)
			(size 0.3556 1.524)
			(layers "F.Cu" "F.Mask" "F.Paste")
			(net "GPIO_P_EXP_A0")
		)
		(pad "22" smd rect
			(at -2.27584 -2.8194 180)
			(size 0.3556 1.524)
			(layers "F.Cu" "F.Mask" "F.Paste")
			(net "SMCLK_EXP_R_PCH")
		)
		(pad "23" smd rect
			(at -2.92608 -2.8194 180)
			(size 0.3556 1.524)
			(layers "F.Cu" "F.Mask" "F.Paste")
			(net "SMDAT_EXP_R_PCH")
		)
		(pad "24" smd rect
			(at -3.57632 -2.8194 180)
			(size 0.3556 1.524)
			(layers "F.Cu" "F.Mask" "F.Paste")
			(net "P3V3_STBY")
		)
	)
	(footprint ""
		(layer "F.Cu")
		(at 131.7498 -11.4808 -90)
		(property "Reference" "R122"
			(at 0 0 270)
			(layer "F.SilkS")
			(hide yes)
			(effects
				(font
					(size 1.27 1.27)
				)
			)
		)
		(property "Value" "10KR2F-2-GP"
			(at 0.064008 -3.993896 270)
			(unlocked yes)
			(layer "F.Fab")
			(hide yes)
			(effects
				(font
					(size 1.016 1.016)
					(thickness 0.1524)
				)
			)
		)
		(property "Device Type" "R402H16"
			(at 0.064008 -5.517896 270)
			(unlocked yes)
			(layer "F.Fab")
			(hide yes)
			(effects
				(font
					(size 1.016 1.016)
					(thickness 0.1524)
				)
			)
		)
		(duplicate_pad_numbers_are_jumpers no)
		(fp_line
			(start -0.508 -0.9398)
			(end -0.508 0.9398)
			(stroke
				(width 0.1524)
				(type default)
			)
			(layer "F.SilkS")
		)
		(fp_line
			(start 0.508 -0.9398)
			(end -0.508 -0.9398)
			(stroke
				(width 0.1524)
				(type default)
			)
			(layer "F.SilkS")
		)
		(fp_rect
			(start -0.508 0.9398)
			(end 0.508 -0.9398)
			(stroke
				(width 0)
				(type default)
			)
			(fill no)
			(layer "F.CrtYd")
		)
		(fp_rect
			(start -0.508 0.9398)
			(end 0.508 -0.9398)
			(stroke
				(width 0)
				(type default)
			)
			(fill no)
			(layer "F.Fab")
		)
		(pad "1" smd custom
			(at 0 -0.4445 270)
			(size 0.1397 0.1397)
			(layers "F.Cu" "F.Mask" "F.Paste")
			(net "P3V3_STBY")
			(options
				(clearance outline)
				(anchor circle)
			)
			(primitives
				(gr_poly
					(pts
						(arc
							(start -0.1778 -0.2794)
							(mid -0.249642 -0.249642)
							(end -0.2794 -0.1778)
						)
						(arc
							(start -0.2794 0.1778)
							(mid -0.249642 0.249642)
							(end -0.1778 0.2794)
						)
						(arc
							(start 0.1778 0.2794)
							(mid 0.249642 0.249642)
							(end 0.2794 0.1778)
						)
						(arc
							(start 0.2794 -0.1778)
							(mid 0.249642 -0.249642)
							(end 0.1778 -0.2794)
						)
					)
					(width 0)
					(fill yes)
				)
			)
		)
		(pad "2" smd custom
			(at 0 0.4445 270)
			(size 0.1397 0.1397)
			(layers "F.Cu" "F.Mask" "F.Paste")
			(net "GPIO_B_IO1_3")
			(options
				(clearance outline)
				(anchor circle)
			)
			(primitives
				(gr_poly
					(pts
						(arc
							(start -0.1778 -0.2794)
							(mid -0.249642 -0.249642)
							(end -0.2794 -0.1778)
						)
						(arc
							(start -0.2794 0.1778)
							(mid -0.249642 0.249642)
							(end -0.1778 0.2794)
						)
						(arc
							(start 0.1778 0.2794)
							(mid 0.249642 0.249642)
							(end 0.2794 0.1778)
						)
						(arc
							(start 0.2794 -0.1778)
							(mid 0.249642 -0.249642)
							(end 0.1778 -0.2794)
						)
					)
					(width 0)
					(fill yes)
				)
			)
		)
	)
)
